FILE_TYPE=LIBRARY_PARTS;
primitive 'ADM1086AKSZREEL7';
  pin
    'VCC':
      PIN_NUMBER='(6)';
      PINUSE='POWER';
      NO_LOAD_CHECK='Both';
      NO_IO_CHECK='Both';
      NO_ASSERT_CHECK='TRUE';
      NO_DIR_CHECK='TRUE';
      ALLOW_CONNECT='TRUE';
    'VIN':
      PIN_NUMBER='(3)';
      PINUSE='POWER';
      NO_LOAD_CHECK='Both';
      NO_IO_CHECK='Both';
      NO_ASSERT_CHECK='TRUE';
      NO_DIR_CHECK='TRUE';
      ALLOW_CONNECT='TRUE';
    'ENIN':
      PIN_NUMBER='(1)';
      INPUT_LOAD='(-0.01,0.01)';
    'ENOUT':
      PIN_NUMBER='(4)';
      OUTPUT_LOAD='(1.0,-1.0)';
    'CEXT':
      PIN_NUMBER='(5)';
      BIDIRECTIONAL='TRUE';
      INPUT_LOAD='(-0.01,0.01)';
      OUTPUT_LOAD='(1.0,-1.0)';
    'GND':
      PIN_NUMBER='(2)';
      PINUSE='POWER';
      NO_LOAD_CHECK='Both';
      NO_IO_CHECK='Both';
      NO_ASSERT_CHECK='TRUE';
      NO_DIR_CHECK='TRUE';
      ALLOW_CONNECT='TRUE';
  end_pin;
  body
    PART_NAME='ADM1086AKSZREEL7';
    BODY_NAME='ADM1086AKSZREEL7';
    PHYS_DES_PREFIX='U';
    CLASS='IC';
  end_body;
end_primitive;

END.
